# T6G (Grand Teton) — schematic netlist excerpt (pin names and nets, part order shuffled) for the footprints in the layout excerpt that follows; sources: Cadence DE-HDL packaged netlist, KiCad conversion of 04192023_DAF0TMB3IC0_F0TG_MB_C_brd_V02_OCP.brd

PC574  Q_CAP  0.22UF 16V 10% X7R  pkg 0402  page 196 : A = SW_PVDDCR_CPU0_P0_BOOT5_RC ; B = SW_PVDDCR_CPU0_P0_PH5
R3732  Q_RES  2.2K 5% CHIP  pkg 0402LF  page 252 : A = P3V3_AUX ; B = SMB_LM75_3_3V3AUX_SDA
R698  Q_RES  33.2 1% CHIP  pkg 0201LF  page 355 : A = SMB_RT_CPU1_P3_ROM_R_SDA ; B = SMB_RT_CPU1_P3_ROM_SDA

(kicad_pcb
	(version 20260206)
	(generator "pcbnew")
	(generator_version "10.0")
	(general
		(thickness 1.6)
		(legacy_teardrops no)
	)
	(paper "A4")
	(title_block
		(title "04192023_DAF0TMB3IC0_F0TG_MB_C_brd_V02_OCP.brd")
		(comment 1 "Grand Teton / footprints 2270-2272 of 8354")
	)
	(layers
		(0 "F.Cu" signal "TOP")
		(4 "In1.Cu" signal "GND")
		(6 "In2.Cu" signal "IN1")
		(8 "In3.Cu" signal "GND1")
		(10 "In4.Cu" signal "IN2")
		(12 "In5.Cu" signal "GND2")
		(14 "In6.Cu" signal "IN3")
		(16 "In7.Cu" signal "GND3")
		(18 "In8.Cu" signal "VCC")
		(20 "In9.Cu" signal "VCC1")
		(22 "In10.Cu" signal "GND4")
		(24 "In11.Cu" signal "IN4")
		(26 "In12.Cu" signal "GND5")
		(28 "In13.Cu" signal "IN5")
		(30 "In14.Cu" signal "GND6")
		(32 "In15.Cu" signal "IN6")
		(34 "In16.Cu" signal "GND7")
		(2 "B.Cu" signal "BOTTOM")
		(9 "F.Adhes" user "F.Adhesive")
		(11 "B.Adhes" user "B.Adhesive")
		(13 "F.Paste" user "Package Geometry/Pastemask Top")
		(15 "B.Paste" user "Package Geometry/Pastemask Bottom")
		(5 "F.SilkS" user "Ref Des/Silkscreen Top")
		(7 "B.SilkS" user "Ref Des/Silkscreen Bottom")
		(1 "F.Mask" user "Board Geometry/Soldermask Top")
		(3 "B.Mask" user "Board Geometry/Soldermask Bottom")
		(17 "Dwgs.User" user "User.Drawings")
		(19 "Cmts.User" user "User.Comments")
		(21 "Eco1.User" user "User.Eco1")
		(23 "Eco2.User" user "User.Eco2")
		(25 "Edge.Cuts" user "Board Geometry/Outline")
		(27 "Margin" user)
		(31 "F.CrtYd" user "Package Geometry/Place Bound Top")
		(29 "B.CrtYd" user "Package Geometry/Place Bound Bottom")
		(35 "F.Fab" user "Ref Des/Assembly Top")
		(33 "B.Fab" user "Ref Des/Assembly Bottom")
	)
	(footprint ""
		(layer "F.Cu")
		(at 354.247704 -164.844222 90)
		(property "Reference" "PC574"
			(at 0 0 90)
			(layer "F.SilkS")
			(hide yes)
			(effects
				(font
					(size 1.27 1.27)
				)
			)
		)
		(property "Value" ""
			(at 0 0 90)
			(layer "F.Fab")
			(effects
				(font
					(size 1.27 1.27)
				)
			)
		)
		(duplicate_pad_numbers_are_jumpers no)
		(fp_line
			(start 0.7874 -0.4064)
			(end 0.7874 0.4064)
			(stroke
				(width 0.1524)
				(type default)
			)
			(layer "F.SilkS")
		)
		(fp_line
			(start -0.7874 -0.4064)
			(end 0.7874 -0.4064)
			(stroke
				(width 0.1524)
				(type default)
			)
			(layer "F.SilkS")
		)
		(fp_line
			(start 0.7874 0.4064)
			(end -0.7874 0.4064)
			(stroke
				(width 0.1524)
				(type default)
			)
			(layer "F.SilkS")
		)
		(fp_line
			(start -0.7874 0.4064)
			(end -0.7874 -0.4064)
			(stroke
				(width 0.1524)
				(type default)
			)
			(layer "F.SilkS")
		)
		(fp_line
			(start -0.12065 -0.305054)
			(end -0.12065 -0.2794)
			(stroke
				(width 0.1)
				(type default)
			)
			(layer "F.Fab")
		)
		(fp_line
			(start -0.67945 -0.305054)
			(end -0.12065 -0.305054)
			(stroke
				(width 0.1)
				(type default)
			)
			(layer "F.Fab")
		)
		(fp_line
			(start 0.67945 -0.3048)
			(end 0.67945 0.3048)
			(stroke
				(width 0.1)
				(type default)
			)
			(layer "F.Fab")
		)
		(fp_line
			(start 0.12065 -0.3048)
			(end 0.67945 -0.3048)
			(stroke
				(width 0.1)
				(type default)
			)
			(layer "F.Fab")
		)
		(fp_line
			(start 0.12065 -0.2794)
			(end 0.12065 -0.3048)
			(stroke
				(width 0.1)
				(type default)
			)
			(layer "F.Fab")
		)
		(fp_line
			(start -0.12065 -0.2794)
			(end 0.12065 -0.2794)
			(stroke
				(width 0.1)
				(type default)
			)
			(layer "F.Fab")
		)
		(fp_line
			(start 0.120396 0.2794)
			(end -0.12065 0.2794)
			(stroke
				(width 0.1)
				(type default)
			)
			(layer "F.Fab")
		)
		(fp_line
			(start -0.12065 0.2794)
			(end -0.12065 0.3048)
			(stroke
				(width 0.1)
				(type default)
			)
			(layer "F.Fab")
		)
		(fp_line
			(start 0.67945 0.3048)
			(end 0.120396 0.3048)
			(stroke
				(width 0.1)
				(type default)
			)
			(layer "F.Fab")
		)
		(fp_line
			(start 0.120396 0.3048)
			(end 0.120396 0.2794)
			(stroke
				(width 0.1)
				(type default)
			)
			(layer "F.Fab")
		)
		(fp_line
			(start -0.12065 0.3048)
			(end -0.67945 0.3048)
			(stroke
				(width 0.1)
				(type default)
			)
			(layer "F.Fab")
		)
		(fp_line
			(start -0.67945 0.3048)
			(end -0.67945 -0.305054)
			(stroke
				(width 0.1)
				(type default)
			)
			(layer "F.Fab")
		)
		(pad "1" smd circle
			(at -0.40005 0 90)
			(size 0 0)
			(layers "F.Cu" "F.Mask" "F.Paste")
			(net "SW_PVDDCR_CPU0_P0_BOOT5_RC")
		)
		(pad "2" smd circle
			(at 0.40005 0 90)
			(size 0 0)
			(layers "F.Cu" "F.Mask" "F.Paste")
			(net "SW_PVDDCR_CPU0_P0_PH5")
		)
	)
	(footprint ""
		(layer "F.Cu")
		(at 168.402762 -419.1508 90)
		(property "Reference" "R698"
			(at 0 0 90)
			(layer "F.SilkS")
			(hide yes)
			(effects
				(font
					(size 1.27 1.27)
				)
			)
		)
		(property "Value" ""
			(at 0 0 90)
			(layer "F.Fab")
			(effects
				(font
					(size 1.27 1.27)
				)
			)
		)
		(duplicate_pad_numbers_are_jumpers no)
		(fp_line
			(start 0.32512 -0.175006)
			(end 0.32512 0.175006)
			(stroke
				(width 0.1)
				(type default)
			)
			(layer "F.Fab")
		)
		(fp_line
			(start -0.32512 -0.175006)
			(end 0.32512 -0.175006)
			(stroke
				(width 0.1)
				(type default)
			)
			(layer "F.Fab")
		)
		(fp_line
			(start 0.32512 0.175006)
			(end -0.32512 0.175006)
			(stroke
				(width 0.1)
				(type default)
			)
			(layer "F.Fab")
		)
		(fp_line
			(start -0.32512 0.175006)
			(end -0.32512 -0.175006)
			(stroke
				(width 0.1)
				(type default)
			)
			(layer "F.Fab")
		)
		(pad "1" smd rect
			(at -0.2667 0 90)
			(size 0.3048 0.381)
			(layers "F.Cu" "F.Mask" "F.Paste")
			(net "SMB_RT_CPU1_P3_ROM_R_SDA")
		)
		(pad "2" smd rect
			(at 0.2667 0 270)
			(size 0.3048 0.381)
			(layers "F.Cu" "F.Mask" "F.Paste")
			(net "SMB_RT_CPU1_P3_ROM_SDA")
		)
	)
	(footprint ""
		(layer "F.Cu")
		(at 271.080484 -113.156746)
		(property "Reference" "R3732"
			(at 0 0 0)
			(layer "F.SilkS")
			(hide yes)
			(effects
				(font
					(size 1.27 1.27)
				)
			)
		)
		(property "Value" ""
			(at 0 0 0)
			(layer "F.Fab")
			(effects
				(font
					(size 1.27 1.27)
				)
			)
		)
		(duplicate_pad_numbers_are_jumpers no)
		(fp_line
			(start -0.7874 -0.4064)
			(end 0.7874 -0.4064)
			(stroke
				(width 0.1524)
				(type default)
			)
			(layer "F.SilkS")
		)
		(fp_line
			(start -0.7874 0.4064)
			(end -0.7874 -0.4064)
			(stroke
				(width 0.1524)
				(type default)
			)
			(layer "F.SilkS")
		)
		(fp_line
			(start 0.7874 -0.4064)
			(end 0.7874 0.4064)
			(stroke
				(width 0.1524)
				(type default)
			)
			(layer "F.SilkS")
		)
		(fp_line
			(start 0.7874 0.4064)
			(end -0.7874 0.4064)
			(stroke
				(width 0.1524)
				(type default)
			)
			(layer "F.SilkS")
		)
		(fp_line
			(start -0.67945 -0.305054)
			(end -0.12065 -0.305054)
			(stroke
				(width 0.1)
				(type default)
			)
			(layer "F.Fab")
		)
		(fp_line
			(start -0.67945 0.3048)
			(end -0.67945 -0.305054)
			(stroke
				(width 0.1)
				(type default)
			)
			(layer "F.Fab")
		)
		(fp_line
			(start -0.12065 -0.305054)
			(end -0.12065 -0.2794)
			(stroke
				(width 0.1)
				(type default)
			)
			(layer "F.Fab")
		)
		(fp_line
			(start -0.12065 -0.2794)
			(end 0.12065 -0.2794)
			(stroke
				(width 0.1)
				(type default)
			)
			(layer "F.Fab")
		)
		(fp_line
			(start -0.12065 0.2794)
			(end -0.12065 0.3048)
			(stroke
				(width 0.1)
				(type default)
			)
			(layer "F.Fab")
		)
		(fp_line
			(start -0.12065 0.3048)
			(end -0.67945 0.3048)
			(stroke
				(width 0.1)
				(type default)
			)
			(layer "F.Fab")
		)
		(fp_line
			(start 0.120396 0.2794)
			(end -0.12065 0.2794)
			(stroke
				(width 0.1)
				(type default)
			)
			(layer "F.Fab")
		)
		(fp_line
			(start 0.120396 0.3048)
			(end 0.120396 0.2794)
			(stroke
				(width 0.1)
				(type default)
			)
			(layer "F.Fab")
		)
		(fp_line
			(start 0.12065 -0.3048)
			(end 0.67945 -0.3048)
			(stroke
				(width 0.1)
				(type default)
			)
			(layer "F.Fab")
		)
		(fp_line
			(start 0.12065 -0.2794)
			(end 0.12065 -0.3048)
			(stroke
				(width 0.1)
				(type default)
			)
			(layer "F.Fab")
		)
		(fp_line
			(start 0.67945 -0.3048)
			(end 0.67945 0.3048)
			(stroke
				(width 0.1)
				(type default)
			)
			(layer "F.Fab")
		)
		(fp_line
			(start 0.67945 0.3048)
			(end 0.120396 0.3048)
			(stroke
				(width 0.1)
				(type default)
			)
			(layer "F.Fab")
		)
		(pad "1" smd circle
			(at -0.40005 0)
			(size 0 0)
			(layers "F.Cu" "F.Mask" "F.Paste")
			(net "P3V3_AUX")
		)
		(pad "2" smd circle
			(at 0.40005 0)
			(size 0 0)
			(layers "F.Cu" "F.Mask" "F.Paste")
			(net "SMB_LM75_3_3V3AUX_SDA")
		)
	)
)
